FILE_TYPE=LIBRARY_PARTS;
primitive 'SCONN11_H67026001','SCONN11_H67026001_SM';
  pin
    'IO1':
      PIN_NUMBER='(1)';
      BIDIRECTIONAL='TRUE';
      INPUT_LOAD='(-0.01,0.01)';
      OUTPUT_LOAD='(1.0,-1.0)';
    'IO2':
      PIN_NUMBER='(2)';
      BIDIRECTIONAL='TRUE';
      INPUT_LOAD='(-0.01,0.01)';
      OUTPUT_LOAD='(1.0,-1.0)';
    'IO3':
      PIN_NUMBER='(3)';
      BIDIRECTIONAL='TRUE';
      INPUT_LOAD='(-0.01,0.01)';
      OUTPUT_LOAD='(1.0,-1.0)';
    'IO4':
      PIN_NUMBER='(4)';
      BIDIRECTIONAL='TRUE';
      INPUT_LOAD='(-0.01,0.01)';
      OUTPUT_LOAD='(1.0,-1.0)';
    'IO5':
      PIN_NUMBER='(5)';
      BIDIRECTIONAL='TRUE';
      INPUT_LOAD='(-0.01,0.01)';
      OUTPUT_LOAD='(1.0,-1.0)';
    'IO6':
      PIN_NUMBER='(6)';
      BIDIRECTIONAL='TRUE';
      INPUT_LOAD='(-0.01,0.01)';
      OUTPUT_LOAD='(1.0,-1.0)';
    'IO7':
      PIN_NUMBER='(7)';
      BIDIRECTIONAL='TRUE';
      INPUT_LOAD='(-0.01,0.01)';
      OUTPUT_LOAD='(1.0,-1.0)';
    'IO8':
      PIN_NUMBER='(8)';
      BIDIRECTIONAL='TRUE';
      INPUT_LOAD='(-0.01,0.01)';
      OUTPUT_LOAD='(1.0,-1.0)';
    'IO9':
      PIN_NUMBER='(9)';
      BIDIRECTIONAL='TRUE';
      INPUT_LOAD='(-0.01,0.01)';
      OUTPUT_LOAD='(1.0,-1.0)';
    'IO10':
      PIN_NUMBER='(10)';
      BIDIRECTIONAL='TRUE';
      INPUT_LOAD='(-0.01,0.01)';
      OUTPUT_LOAD='(1.0,-1.0)';
    'IO11':
      PIN_NUMBER='(11)';
      BIDIRECTIONAL='TRUE';
      INPUT_LOAD='(-0.01,0.01)';
      OUTPUT_LOAD='(1.0,-1.0)';
    'MP1':
      PIN_NUMBER='(MP1)';
      PINUSE='GROUND';
      NO_LOAD_CHECK='Both';
      NO_IO_CHECK='Both';
      NO_ASSERT_CHECK='TRUE';
      NO_DIR_CHECK='TRUE';
      ALLOW_CONNECT='TRUE';
    'MP2':
      PIN_NUMBER='(MP2)';
      PINUSE='GROUND';
      NO_LOAD_CHECK='Both';
      NO_IO_CHECK='Both';
      NO_ASSERT_CHECK='TRUE';
      NO_DIR_CHECK='TRUE';
      ALLOW_CONNECT='TRUE';
  end_pin;
  body
    PART_NAME='SCONN11_H67026001';
    BODY_NAME='SCONN11_H67026001';
    PHYS_DES_PREFIX='J';
  end_body;
end_primitive;

END.
